# S9S_MB_2U (Grand Teton) — schematic netlist excerpt (pin names and nets, part order shuffled) for the footprints in the layout excerpt that follows; sources: Cadence DE-HDL packaged netlist, KiCad conversion of 03242023_DA0F0TMBIJ0_F0T_Motherboard_J_brd_V01_OCP.brd

R1140  Q_RES  27.4 1% CHIP  pkg 0402LF  page 155 : A = CLK_50M_BMC_MAC_R ; B = CLK_50M_RMII_BMC_OCP
R3187  Q_RES  33.2 1% CHIP  pkg 0402LF  page 161 : A = RST_OCP_V3_2_BUF_N ; B = RST_PERST1_OCP_V3_2_N

(kicad_pcb
	(version 20260206)
	(generator "pcbnew")
	(generator_version "10.0")
	(general
		(thickness 1.6)
		(legacy_teardrops no)
	)
	(paper "A4")
	(title_block
		(title "03242023_DA0F0TMBIJ0_F0T_Motherboard_J_brd_V01_OCP.brd")
		(comment 1 "Grand Teton / footprints 3340-3341 of 6105")
	)
	(layers
		(0 "F.Cu" signal "TOP")
		(4 "In1.Cu" signal "GND")
		(6 "In2.Cu" signal "IN1")
		(8 "In3.Cu" signal "GND1")
		(10 "In4.Cu" signal "IN2")
		(12 "In5.Cu" signal "GND2")
		(14 "In6.Cu" signal "IN3")
		(16 "In7.Cu" signal "GND3")
		(18 "In8.Cu" signal "VCC")
		(20 "In9.Cu" signal "VCC1")
		(22 "In10.Cu" signal "GND4")
		(24 "In11.Cu" signal "IN4")
		(26 "In12.Cu" signal "GND5")
		(28 "In13.Cu" signal "IN5")
		(30 "In14.Cu" signal "GND6")
		(32 "In15.Cu" signal "IN6")
		(34 "In16.Cu" signal "GND7")
		(2 "B.Cu" signal "BOTTOM")
		(9 "F.Adhes" user "F.Adhesive")
		(11 "B.Adhes" user "B.Adhesive")
		(13 "F.Paste" user "Package Geometry/Pastemask Top")
		(15 "B.Paste" user "Package Geometry/Pastemask Bottom")
		(5 "F.SilkS" user "Ref Des/Silkscreen Top")
		(7 "B.SilkS" user "Ref Des/Silkscreen Bottom")
		(1 "F.Mask" user "Board Geometry/Soldermask Top")
		(3 "B.Mask" user "Board Geometry/Soldermask Bottom")
		(17 "Dwgs.User" user "User.Drawings")
		(19 "Cmts.User" user "User.Comments")
		(21 "Eco1.User" user "User.Eco1")
		(23 "Eco2.User" user "User.Eco2")
		(25 "Edge.Cuts" user "Board Geometry/Outline")
		(27 "Margin" user)
		(31 "F.CrtYd" user "Package Geometry/Place Bound Top")
		(29 "B.CrtYd" user "Package Geometry/Place Bound Bottom")
		(35 "F.Fab" user "Ref Des/Assembly Top")
		(33 "B.Fab" user "Ref Des/Assembly Bottom")
	)
	(footprint ""
		(layer "F.Cu")
		(at 106.476038 -41.012364)
		(property "Reference" "R3187"
			(at 0 0 0)
			(layer "F.SilkS")
			(hide yes)
			(effects
				(font
					(size 1.27 1.27)
				)
			)
		)
		(property "Value" ""
			(at 0 0 0)
			(layer "F.Fab")
			(effects
				(font
					(size 1.27 1.27)
				)
			)
		)
		(duplicate_pad_numbers_are_jumpers no)
		(fp_line
			(start -0.7874 -0.4064)
			(end 0.7874 -0.4064)
			(stroke
				(width 0.1524)
				(type default)
			)
			(layer "F.SilkS")
		)
		(fp_line
			(start -0.7874 0.4064)
			(end -0.7874 -0.4064)
			(stroke
				(width 0.1524)
				(type default)
			)
			(layer "F.SilkS")
		)
		(fp_line
			(start 0.7874 -0.4064)
			(end 0.7874 0.4064)
			(stroke
				(width 0.1524)
				(type default)
			)
			(layer "F.SilkS")
		)
		(fp_line
			(start 0.7874 0.4064)
			(end -0.7874 0.4064)
			(stroke
				(width 0.1524)
				(type default)
			)
			(layer "F.SilkS")
		)
		(fp_line
			(start -0.67945 -0.305054)
			(end -0.12065 -0.305054)
			(stroke
				(width 0.1)
				(type default)
			)
			(layer "F.Fab")
		)
		(fp_line
			(start -0.67945 0.3048)
			(end -0.67945 -0.305054)
			(stroke
				(width 0.1)
				(type default)
			)
			(layer "F.Fab")
		)
		(fp_line
			(start -0.12065 -0.305054)
			(end -0.12065 -0.2794)
			(stroke
				(width 0.1)
				(type default)
			)
			(layer "F.Fab")
		)
		(fp_line
			(start -0.12065 -0.2794)
			(end 0.12065 -0.2794)
			(stroke
				(width 0.1)
				(type default)
			)
			(layer "F.Fab")
		)
		(fp_line
			(start -0.12065 0.2794)
			(end -0.12065 0.3048)
			(stroke
				(width 0.1)
				(type default)
			)
			(layer "F.Fab")
		)
		(fp_line
			(start -0.12065 0.3048)
			(end -0.67945 0.3048)
			(stroke
				(width 0.1)
				(type default)
			)
			(layer "F.Fab")
		)
		(fp_line
			(start 0.120396 0.2794)
			(end -0.12065 0.2794)
			(stroke
				(width 0.1)
				(type default)
			)
			(layer "F.Fab")
		)
		(fp_line
			(start 0.120396 0.3048)
			(end 0.120396 0.2794)
			(stroke
				(width 0.1)
				(type default)
			)
			(layer "F.Fab")
		)
		(fp_line
			(start 0.12065 -0.3048)
			(end 0.67945 -0.3048)
			(stroke
				(width 0.1)
				(type default)
			)
			(layer "F.Fab")
		)
		(fp_line
			(start 0.12065 -0.2794)
			(end 0.12065 -0.3048)
			(stroke
				(width 0.1)
				(type default)
			)
			(layer "F.Fab")
		)
		(fp_line
			(start 0.67945 -0.3048)
			(end 0.67945 0.3048)
			(stroke
				(width 0.1)
				(type default)
			)
			(layer "F.Fab")
		)
		(fp_line
			(start 0.67945 0.3048)
			(end 0.120396 0.3048)
			(stroke
				(width 0.1)
				(type default)
			)
			(layer "F.Fab")
		)
		(pad "1" smd circle
			(at -0.40005 0)
			(size 0 0)
			(layers "F.Cu" "F.Mask" "F.Paste")
			(net "RST_OCP_V3_2_BUF_N")
		)
		(pad "2" smd circle
			(at 0.40005 0)
			(size 0 0)
			(layers "F.Cu" "F.Mask" "F.Paste")
			(net "RST_PERST1_OCP_V3_2_N")
		)
	)
	(footprint ""
		(layer "F.Cu")
		(at 213.06155 -22.974554 180)
		(property "Reference" "R1140"
			(at 0 0 180)
			(layer "F.SilkS")
			(hide yes)
			(effects
				(font
					(size 1.27 1.27)
				)
			)
		)
		(property "Value" ""
			(at 0 0 180)
			(layer "F.Fab")
			(effects
				(font
					(size 1.27 1.27)
				)
			)
		)
		(duplicate_pad_numbers_are_jumpers no)
		(fp_line
			(start 0.7874 0.4064)
			(end -0.7874 0.4064)
			(stroke
				(width 0.1524)
				(type default)
			)
			(layer "F.SilkS")
		)
		(fp_line
			(start 0.7874 -0.4064)
			(end 0.7874 0.4064)
			(stroke
				(width 0.1524)
				(type default)
			)
			(layer "F.SilkS")
		)
		(fp_line
			(start -0.7874 0.4064)
			(end -0.7874 -0.4064)
			(stroke
				(width 0.1524)
				(type default)
			)
			(layer "F.SilkS")
		)
		(fp_line
			(start -0.7874 -0.4064)
			(end 0.7874 -0.4064)
			(stroke
				(width 0.1524)
				(type default)
			)
			(layer "F.SilkS")
		)
		(fp_line
			(start 0.67945 0.3048)
			(end 0.120396 0.3048)
			(stroke
				(width 0.1)
				(type default)
			)
			(layer "F.Fab")
		)
		(fp_line
			(start 0.67945 -0.3048)
			(end 0.67945 0.3048)
			(stroke
				(width 0.1)
				(type default)
			)
			(layer "F.Fab")
		)
		(fp_line
			(start 0.12065 -0.2794)
			(end 0.12065 -0.3048)
			(stroke
				(width 0.1)
				(type default)
			)
			(layer "F.Fab")
		)
		(fp_line
			(start 0.12065 -0.3048)
			(end 0.67945 -0.3048)
			(stroke
				(width 0.1)
				(type default)
			)
			(layer "F.Fab")
		)
		(fp_line
			(start 0.120396 0.3048)
			(end 0.120396 0.2794)
			(stroke
				(width 0.1)
				(type default)
			)
			(layer "F.Fab")
		)
		(fp_line
			(start 0.120396 0.2794)
			(end -0.12065 0.2794)
			(stroke
				(width 0.1)
				(type default)
			)
			(layer "F.Fab")
		)
		(fp_line
			(start -0.12065 0.3048)
			(end -0.67945 0.3048)
			(stroke
				(width 0.1)
				(type default)
			)
			(layer "F.Fab")
		)
		(fp_line
			(start -0.12065 0.2794)
			(end -0.12065 0.3048)
			(stroke
				(width 0.1)
				(type default)
			)
			(layer "F.Fab")
		)
		(fp_line
			(start -0.12065 -0.2794)
			(end 0.12065 -0.2794)
			(stroke
				(width 0.1)
				(type default)
			)
			(layer "F.Fab")
		)
		(fp_line
			(start -0.12065 -0.305054)
			(end -0.12065 -0.2794)
			(stroke
				(width 0.1)
				(type default)
			)
			(layer "F.Fab")
		)
		(fp_line
			(start -0.67945 0.3048)
			(end -0.67945 -0.305054)
			(stroke
				(width 0.1)
				(type default)
			)
			(layer "F.Fab")
		)
		(fp_line
			(start -0.67945 -0.305054)
			(end -0.12065 -0.305054)
			(stroke
				(width 0.1)
				(type default)
			)
			(layer "F.Fab")
		)
		(pad "1" smd circle
			(at -0.40005 0 180)
			(size 0 0)
			(layers "F.Cu" "F.Mask" "F.Paste")
			(net "CLK_50M_BMC_MAC_R")
		)
		(pad "2" smd circle
			(at 0.40005 0 180)
			(size 0 0)
			(layers "F.Cu" "F.Mask" "F.Paste")
			(net "CLK_50M_RMII_BMC_OCP")
		)
	)
)
